# T6G (Grand Teton) — schematic netlist excerpt (pin names and nets, part order shuffled) for the footprints in the layout excerpt that follows; sources: Cadence DE-HDL packaged netlist, KiCad conversion of 04192023_DAF0TMB3IC0_F0TG_MB_C_brd_V02_OCP.brd

R1228  Q_RES  0 5% EMPTY  pkg 0402LF  page 258 : A = SMB_ADC_SCL_R ; B = SMB_SEN_MAM_2_3V3AUX_SCL
C595  Q_CAP  10UF 6.3V 20% X6S  pkg C0402  page 290 : A = P1V8_CPU0_RT1_1A ; B = GND

(kicad_pcb
	(version 20260206)
	(generator "pcbnew")
	(generator_version "10.0")
	(general
		(thickness 1.6)
		(legacy_teardrops no)
	)
	(paper "A4")
	(title_block
		(title "04192023_DAF0TMB3IC0_F0TG_MB_C_brd_V02_OCP.brd")
		(comment 1 "Grand Teton / footprints 7326-7327 of 8354")
	)
	(layers
		(0 "F.Cu" signal "TOP")
		(4 "In1.Cu" signal "GND")
		(6 "In2.Cu" signal "IN1")
		(8 "In3.Cu" signal "GND1")
		(10 "In4.Cu" signal "IN2")
		(12 "In5.Cu" signal "GND2")
		(14 "In6.Cu" signal "IN3")
		(16 "In7.Cu" signal "GND3")
		(18 "In8.Cu" signal "VCC")
		(20 "In9.Cu" signal "VCC1")
		(22 "In10.Cu" signal "GND4")
		(24 "In11.Cu" signal "IN4")
		(26 "In12.Cu" signal "GND5")
		(28 "In13.Cu" signal "IN5")
		(30 "In14.Cu" signal "GND6")
		(32 "In15.Cu" signal "IN6")
		(34 "In16.Cu" signal "GND7")
		(2 "B.Cu" signal "BOTTOM")
		(9 "F.Adhes" user "F.Adhesive")
		(11 "B.Adhes" user "B.Adhesive")
		(13 "F.Paste" user "Package Geometry/Pastemask Top")
		(15 "B.Paste" user "Package Geometry/Pastemask Bottom")
		(5 "F.SilkS" user "Ref Des/Silkscreen Top")
		(7 "B.SilkS" user "Ref Des/Silkscreen Bottom")
		(1 "F.Mask" user "Board Geometry/Soldermask Top")
		(3 "B.Mask" user "Board Geometry/Soldermask Bottom")
		(17 "Dwgs.User" user "User.Drawings")
		(19 "Cmts.User" user "User.Comments")
		(21 "Eco1.User" user "User.Eco1")
		(23 "Eco2.User" user "User.Eco2")
		(25 "Edge.Cuts" user "Board Geometry/Outline")
		(27 "Margin" user)
		(31 "F.CrtYd" user "Package Geometry/Place Bound Top")
		(29 "B.CrtYd" user "Package Geometry/Place Bound Bottom")
		(35 "F.Fab" user "Ref Des/Assembly Top")
		(33 "B.Fab" user "Ref Des/Assembly Bottom")
	)
	(footprint ""
		(layer "B.Cu")
		(at 345.51874 -398.942052 90)
		(property "Reference" "C595"
			(at 0 0 90)
			(layer "B.SilkS")
			(hide yes)
			(effects
				(font
					(size 1.27 1.27)
				)
				(justify mirror)
			)
		)
		(property "Value" ""
			(at 0 0 90)
			(layer "B.Fab")
			(effects
				(font
					(size 1.27 1.27)
				)
				(justify mirror)
			)
		)
		(duplicate_pad_numbers_are_jumpers no)
		(fp_line
			(start 0.7874 -0.4064)
			(end -0.7874 -0.4064)
			(stroke
				(width 0.1524)
				(type default)
			)
			(layer "B.SilkS")
		)
		(fp_line
			(start -0.7874 -0.4064)
			(end -0.7874 0.4064)
			(stroke
				(width 0.1524)
				(type default)
			)
			(layer "B.SilkS")
		)
		(fp_line
			(start 0.7874 0.4064)
			(end 0.7874 -0.4064)
			(stroke
				(width 0.1524)
				(type default)
			)
			(layer "B.SilkS")
		)
		(fp_line
			(start -0.7874 0.4064)
			(end 0.7874 0.4064)
			(stroke
				(width 0.1524)
				(type default)
			)
			(layer "B.SilkS")
		)
		(fp_line
			(start 0.67945 -0.305054)
			(end 0.12065 -0.305054)
			(stroke
				(width 0.1)
				(type default)
			)
			(layer "B.Fab")
		)
		(fp_line
			(start 0.12065 -0.305054)
			(end 0.12065 -0.2794)
			(stroke
				(width 0.1)
				(type default)
			)
			(layer "B.Fab")
		)
		(fp_line
			(start -0.12065 -0.3048)
			(end -0.67945 -0.3048)
			(stroke
				(width 0.1)
				(type default)
			)
			(layer "B.Fab")
		)
		(fp_line
			(start -0.67945 -0.3048)
			(end -0.67945 0.3048)
			(stroke
				(width 0.1)
				(type default)
			)
			(layer "B.Fab")
		)
		(fp_line
			(start 0.12065 -0.2794)
			(end -0.12065 -0.2794)
			(stroke
				(width 0.1)
				(type default)
			)
			(layer "B.Fab")
		)
		(fp_line
			(start -0.12065 -0.2794)
			(end -0.12065 -0.3048)
			(stroke
				(width 0.1)
				(type default)
			)
			(layer "B.Fab")
		)
		(fp_line
			(start 0.12065 0.2794)
			(end 0.12065 0.3048)
			(stroke
				(width 0.1)
				(type default)
			)
			(layer "B.Fab")
		)
		(fp_line
			(start -0.120396 0.2794)
			(end 0.12065 0.2794)
			(stroke
				(width 0.1)
				(type default)
			)
			(layer "B.Fab")
		)
		(fp_line
			(start 0.67945 0.3048)
			(end 0.67945 -0.305054)
			(stroke
				(width 0.1)
				(type default)
			)
			(layer "B.Fab")
		)
		(fp_line
			(start 0.12065 0.3048)
			(end 0.67945 0.3048)
			(stroke
				(width 0.1)
				(type default)
			)
			(layer "B.Fab")
		)
		(fp_line
			(start -0.120396 0.3048)
			(end -0.120396 0.2794)
			(stroke
				(width 0.1)
				(type default)
			)
			(layer "B.Fab")
		)
		(fp_line
			(start -0.67945 0.3048)
			(end -0.120396 0.3048)
			(stroke
				(width 0.1)
				(type default)
			)
			(layer "B.Fab")
		)
		(pad "1" smd circle
			(at 0.40005 0 270)
			(size 0 0)
			(layers "B.Cu" "B.Mask" "B.Paste")
			(net "P1V8_CPU0_RT1_1A")
		)
		(pad "2" smd circle
			(at -0.40005 0 270)
			(size 0 0)
			(layers "B.Cu" "B.Mask" "B.Paste")
			(net "GND")
		)
	)
	(footprint ""
		(layer "B.Cu")
		(at 243.713 -325.882 180)
		(property "Reference" "R1228"
			(at 0 0 0)
			(layer "B.SilkS")
			(hide yes)
			(effects
				(font
					(size 1.27 1.27)
				)
				(justify mirror)
			)
		)
		(property "Value" ""
			(at 0 0 0)
			(layer "B.Fab")
			(effects
				(font
					(size 1.27 1.27)
				)
				(justify mirror)
			)
		)
		(duplicate_pad_numbers_are_jumpers no)
		(fp_line
			(start 0.7874 0.4064)
			(end 0.7874 -0.4064)
			(stroke
				(width 0.1524)
				(type default)
			)
			(layer "B.SilkS")
		)
		(fp_line
			(start 0.7874 -0.4064)
			(end -0.7874 -0.4064)
			(stroke
				(width 0.1524)
				(type default)
			)
			(layer "B.SilkS")
		)
		(fp_line
			(start -0.7874 0.4064)
			(end 0.7874 0.4064)
			(stroke
				(width 0.1524)
				(type default)
			)
			(layer "B.SilkS")
		)
		(fp_line
			(start -0.7874 -0.4064)
			(end -0.7874 0.4064)
			(stroke
				(width 0.1524)
				(type default)
			)
			(layer "B.SilkS")
		)
		(fp_line
			(start 0.67945 0.3048)
			(end 0.67945 -0.305054)
			(stroke
				(width 0.1)
				(type default)
			)
			(layer "B.Fab")
		)
		(fp_line
			(start 0.67945 -0.305054)
			(end 0.12065 -0.305054)
			(stroke
				(width 0.1)
				(type default)
			)
			(layer "B.Fab")
		)
		(fp_line
			(start 0.12065 0.3048)
			(end 0.67945 0.3048)
			(stroke
				(width 0.1)
				(type default)
			)
			(layer "B.Fab")
		)
		(fp_line
			(start 0.12065 0.2794)
			(end 0.12065 0.3048)
			(stroke
				(width 0.1)
				(type default)
			)
			(layer "B.Fab")
		)
		(fp_line
			(start 0.12065 -0.2794)
			(end -0.12065 -0.2794)
			(stroke
				(width 0.1)
				(type default)
			)
			(layer "B.Fab")
		)
		(fp_line
			(start 0.12065 -0.305054)
			(end 0.12065 -0.2794)
			(stroke
				(width 0.1)
				(type default)
			)
			(layer "B.Fab")
		)
		(fp_line
			(start -0.120396 0.3048)
			(end -0.120396 0.2794)
			(stroke
				(width 0.1)
				(type default)
			)
			(layer "B.Fab")
		)
		(fp_line
			(start -0.120396 0.2794)
			(end 0.12065 0.2794)
			(stroke
				(width 0.1)
				(type default)
			)
			(layer "B.Fab")
		)
		(fp_line
			(start -0.12065 -0.2794)
			(end -0.12065 -0.3048)
			(stroke
				(width 0.1)
				(type default)
			)
			(layer "B.Fab")
		)
		(fp_line
			(start -0.12065 -0.3048)
			(end -0.67945 -0.3048)
			(stroke
				(width 0.1)
				(type default)
			)
			(layer "B.Fab")
		)
		(fp_line
			(start -0.67945 0.3048)
			(end -0.120396 0.3048)
			(stroke
				(width 0.1)
				(type default)
			)
			(layer "B.Fab")
		)
		(fp_line
			(start -0.67945 -0.3048)
			(end -0.67945 0.3048)
			(stroke
				(width 0.1)
				(type default)
			)
			(layer "B.Fab")
		)
		(pad "1" smd circle
			(at 0.40005 0)
			(size 0 0)
			(layers "B.Cu" "B.Mask" "B.Paste")
			(net "SMB_ADC_SCL_R")
		)
		(pad "2" smd circle
			(at -0.40005 0)
			(size 0 0)
			(layers "B.Cu" "B.Mask" "B.Paste")
			(net "SMB_SEN_MAM_2_3V3AUX_SCL")
		)
	)
)
